(kicad_pcb
	(version 20260206)
	(generator "pcbnew")
	(generator_version "10.0")
	(general
		(thickness 1.6)
		(legacy_teardrops no)
	)
	(paper "A4")
	(title_block
		(title "Bryce Canyon_SCC_16316-1_OCP.brd")
		(comment 1 "Bryce Canyon / footprints 1282-1289 of 1561")
	)
	(layers
		(0 "F.Cu" signal "TOP")
		(4 "In1.Cu" signal "L2GND")
		(6 "In2.Cu" signal "L3")
		(8 "In3.Cu" signal "L4VCC")
		(10 "In4.Cu" signal "L5VCC")
		(12 "In5.Cu" signal "L6")
		(14 "In6.Cu" signal "L7GND")
		(2 "B.Cu" signal "BOTTOM")
		(9 "F.Adhes" user "F.Adhesive")
		(11 "B.Adhes" user "B.Adhesive")
		(13 "F.Paste" user "Package Geometry/Pastemask Top")
		(15 "B.Paste" user "Package Geometry/Pastemask Bottom")
		(5 "F.SilkS" user "Ref Des/Silkscreen Top")
		(7 "B.SilkS" user "Ref Des/Silkscreen Bottom")
		(1 "F.Mask" user "Board Geometry/Soldermask Top")
		(3 "B.Mask" user "Board Geometry/Soldermask Bottom")
		(17 "Dwgs.User" user "User.Drawings")
		(19 "Cmts.User" user "User.Comments")
		(21 "Eco1.User" user "User.Eco1")
		(23 "Eco2.User" user "User.Eco2")
		(25 "Edge.Cuts" user "Board Geometry/Outline")
		(27 "Margin" user)
		(31 "F.CrtYd" user "Package Geometry/Place Bound Top")
		(29 "B.CrtYd" user "Package Geometry/Place Bound Bottom")
		(35 "F.Fab" user "Ref Des/Assembly Top")
		(33 "B.Fab" user "Ref Des/Assembly Bottom")
	)
	(footprint ""
		(layer "B.Cu")
		(at 111.76 -70.3834 180)
		(property "Reference" "C181"
			(at 0 0 0)
			(layer "B.SilkS")
			(hide yes)
			(effects
				(font
					(size 1.27 1.27)
				)
				(justify mirror)
			)
		)
		(property "Value" "SCD1U6D3V1KX-GP"
			(at 2.8321 -1.7399 180)
			(unlocked yes)
			(layer "B.Fab")
			(hide yes)
			(effects
				(font
					(size 1.016 1.016)
					(thickness 0.1524)
				)
				(justify mirror)
			)
		)
		(property "Device Type" "C0201H13"
			(at 2.8321 -3.2639 180)
			(unlocked yes)
			(layer "B.Fab")
			(hide yes)
			(effects
				(font
					(size 1.016 1.016)
					(thickness 0.1524)
				)
				(justify mirror)
			)
		)
		(duplicate_pad_numbers_are_jumpers no)
		(fp_rect
			(start 0.2794 0.6477)
			(end -0.2794 -0.6477)
			(stroke
				(width 0)
				(type default)
			)
			(fill no)
			(layer "B.CrtYd")
		)
		(fp_rect
			(start 0.2794 0.6477)
			(end -0.2794 -0.6477)
			(stroke
				(width 0)
				(type default)
			)
			(fill no)
			(layer "B.Fab")
		)
		(pad "1" smd custom
			(at 0 -0.2794)
			(size 0.0762 0.0762)
			(layers "B.Cu" "B.Mask" "B.Paste")
			(net "P0V9")
			(options
				(clearance outline)
				(anchor circle)
			)
			(primitives
				(gr_poly
					(pts
						(arc
							(start 0.1524 0.127)
							(mid 0.137521 0.162921)
							(end 0.1016 0.1778)
						)
						(arc
							(start -0.1016 0.1778)
							(mid -0.137521 0.162921)
							(end -0.1524 0.127)
						)
						(arc
							(start -0.1524 -0.127)
							(mid -0.137521 -0.162921)
							(end -0.1016 -0.1778)
						)
						(arc
							(start 0.1016 -0.1778)
							(mid 0.137521 -0.162921)
							(end 0.1524 -0.127)
						)
					)
					(width 0)
					(fill yes)
				)
			)
		)
		(pad "2" smd custom
			(at 0 0.2794)
			(size 0.0762 0.0762)
			(layers "B.Cu" "B.Mask" "B.Paste")
			(net "GND")
			(options
				(clearance outline)
				(anchor circle)
			)
			(primitives
				(gr_poly
					(pts
						(arc
							(start 0.1524 0.127)
							(mid 0.137521 0.162921)
							(end 0.1016 0.1778)
						)
						(arc
							(start -0.1016 0.1778)
							(mid -0.137521 0.162921)
							(end -0.1524 0.127)
						)
						(arc
							(start -0.1524 -0.127)
							(mid -0.137521 -0.162921)
							(end -0.1016 -0.1778)
						)
						(arc
							(start 0.1016 -0.1778)
							(mid 0.137521 -0.162921)
							(end 0.1524 -0.127)
						)
					)
					(width 0)
					(fill yes)
				)
			)
		)
	)
	(footprint ""
		(layer "B.Cu")
		(at 76.327 -62.103 180)
		(property "Reference" "C235"
			(at 0 0 0)
			(layer "B.SilkS")
			(hide yes)
			(effects
				(font
					(size 1.27 1.27)
				)
				(justify mirror)
			)
		)
		(property "Value" "SC22U6D3V3MX-9-GP-U"
			(at 0 -2.8194 180)
			(unlocked yes)
			(layer "B.Fab")
			(hide yes)
			(effects
				(font
					(size 1.016 1.016)
					(thickness 0.1524)
				)
				(justify mirror)
			)
		)
		(property "Device Type" "C603H40"
			(at 0 -4.3434 180)
			(unlocked yes)
			(layer "B.Fab")
			(hide yes)
			(effects
				(font
					(size 1.016 1.016)
					(thickness 0.1524)
				)
				(justify mirror)
			)
		)
		(duplicate_pad_numbers_are_jumpers no)
		(fp_line
			(start -0.508 0)
			(end 0.508 0)
			(stroke
				(width 0.2032)
				(type default)
			)
			(layer "B.SilkS")
		)
		(fp_rect
			(start 0.5842 1.3335)
			(end -0.5842 -1.3335)
			(stroke
				(width 0)
				(type default)
			)
			(fill no)
			(layer "B.CrtYd")
		)
		(fp_rect
			(start 0.5842 1.3335)
			(end -0.5842 -1.3335)
			(stroke
				(width 0)
				(type default)
			)
			(fill no)
			(layer "B.Fab")
		)
		(pad "1" smd custom
			(at 0 -0.762)
			(size 0.2159 0.2159)
			(layers "B.Cu" "B.Mask" "B.Paste")
			(net "GB_VDDA")
			(options
				(clearance outline)
				(anchor circle)
			)
			(primitives
				(gr_poly
					(pts
						(arc
							(start -0.3302 0.4318)
							(mid -0.402042 0.402042)
							(end -0.4318 0.3302)
						)
						(arc
							(start -0.4318 -0.3302)
							(mid -0.402042 -0.402042)
							(end -0.3302 -0.4318)
						)
						(arc
							(start 0.3302 -0.4318)
							(mid 0.402042 -0.402042)
							(end 0.4318 -0.3302)
						)
						(arc
							(start 0.4318 0.3302)
							(mid 0.402042 0.402042)
							(end 0.3302 0.4318)
						)
					)
					(width 0)
					(fill yes)
				)
			)
		)
		(pad "2" smd custom
			(at 0 0.762)
			(size 0.2159 0.2159)
			(layers "B.Cu" "B.Mask" "B.Paste")
			(net "GND")
			(options
				(clearance outline)
				(anchor circle)
			)
			(primitives
				(gr_poly
					(pts
						(arc
							(start -0.3302 0.4318)
							(mid -0.402042 0.402042)
							(end -0.4318 0.3302)
						)
						(arc
							(start -0.4318 -0.3302)
							(mid -0.402042 -0.402042)
							(end -0.3302 -0.4318)
						)
						(arc
							(start 0.3302 -0.4318)
							(mid 0.402042 -0.402042)
							(end 0.4318 -0.3302)
						)
						(arc
							(start 0.4318 0.3302)
							(mid 0.402042 0.402042)
							(end 0.3302 0.4318)
						)
					)
					(width 0)
					(fill yes)
				)
			)
		)
	)
	(footprint ""
		(layer "B.Cu")
		(at 64.262 -105.41 -90)
		(property "Reference" "C641"
			(at 0 0 90)
			(layer "B.SilkS")
			(hide yes)
			(effects
				(font
					(size 1.27 1.27)
				)
				(justify mirror)
			)
		)
		(property "Value" "SCD1U16V2KX-3GP"
			(at -1.1811 -2.7051 270)
			(unlocked yes)
			(layer "B.Fab")
			(hide yes)
			(effects
				(font
					(size 1.016 1.016)
					(thickness 0.1524)
				)
				(justify mirror)
			)
		)
		(property "Device Type" "C402H22"
			(at -1.1811 -4.2291 270)
			(unlocked yes)
			(layer "B.Fab")
			(hide yes)
			(effects
				(font
					(size 1.016 1.016)
					(thickness 0.1524)
				)
				(justify mirror)
			)
		)
		(duplicate_pad_numbers_are_jumpers no)
		(fp_rect
			(start 0.4318 0.9525)
			(end -0.4318 -0.9525)
			(stroke
				(width 0)
				(type default)
			)
			(fill no)
			(layer "B.CrtYd")
		)
		(fp_rect
			(start 0.4318 0.9525)
			(end -0.4318 -0.9525)
			(stroke
				(width 0)
				(type default)
			)
			(fill no)
			(layer "B.Fab")
		)
		(pad "1" smd custom
			(at 0 -0.4445 90)
			(size 0.1524 0.1524)
			(layers "B.Cu" "B.Mask" "B.Paste")
			(net "P3V3_VBST_RC")
			(options
				(clearance outline)
				(anchor circle)
			)
			(primitives
				(gr_poly
					(pts
						(arc
							(start 0.3048 0.2032)
							(mid 0.275042 0.275042)
							(end 0.2032 0.3048)
						)
						(arc
							(start -0.2032 0.3048)
							(mid -0.275042 0.275042)
							(end -0.3048 0.2032)
						)
						(arc
							(start -0.3048 -0.2032)
							(mid -0.275042 -0.275042)
							(end -0.2032 -0.3048)
						)
						(arc
							(start 0.2032 -0.3048)
							(mid 0.275042 -0.275042)
							(end 0.3048 -0.2032)
						)
					)
					(width 0)
					(fill yes)
				)
			)
		)
		(pad "2" smd custom
			(at 0 0.4445 90)
			(size 0.1524 0.1524)
			(layers "B.Cu" "B.Mask" "B.Paste")
			(net "P3V3_LL")
			(options
				(clearance outline)
				(anchor circle)
			)
			(primitives
				(gr_poly
					(pts
						(arc
							(start 0.3048 0.2032)
							(mid 0.275042 0.275042)
							(end 0.2032 0.3048)
						)
						(arc
							(start -0.2032 0.3048)
							(mid -0.275042 0.275042)
							(end -0.3048 0.2032)
						)
						(arc
							(start -0.3048 -0.2032)
							(mid -0.275042 -0.275042)
							(end -0.2032 -0.3048)
						)
						(arc
							(start 0.2032 -0.3048)
							(mid 0.275042 -0.275042)
							(end 0.3048 -0.2032)
						)
					)
					(width 0)
					(fill yes)
				)
			)
		)
	)
	(footprint ""
		(layer "B.Cu")
		(at 171.5008 -93.161866 -90)
		(property "Reference" "C665"
			(at 0 0 90)
			(layer "B.SilkS")
			(hide yes)
			(effects
				(font
					(size 1.27 1.27)
				)
				(justify mirror)
			)
		)
		(property "Value" "SC22U6D3V6KX-2-GP"
			(at 0.0762 -5.1308 270)
			(unlocked yes)
			(layer "B.Fab")
			(hide yes)
			(effects
				(font
					(size 1.016 1.016)
					(thickness 0.1524)
				)
				(justify mirror)
			)
		)
		(property "Device Type" "C1206H71"
			(at 0.127 -6.6548 270)
			(unlocked yes)
			(layer "B.Fab")
			(hide yes)
			(effects
				(font
					(size 1.016 1.016)
					(thickness 0.1524)
				)
				(justify mirror)
			)
		)
		(duplicate_pad_numbers_are_jumpers no)
		(fp_line
			(start -1.016 2.2352)
			(end 1.016 2.2352)
			(stroke
				(width 0.1524)
				(type default)
			)
			(layer "B.SilkS")
		)
		(fp_line
			(start 1.016 2.2352)
			(end 1.016 0.8382)
			(stroke
				(width 0.1524)
				(type default)
			)
			(layer "B.SilkS")
		)
		(fp_line
			(start -1.016 0.8382)
			(end -1.016 2.2352)
			(stroke
				(width 0.1524)
				(type default)
			)
			(layer "B.SilkS")
		)
		(fp_line
			(start 1.016 -0.8382)
			(end 1.016 -2.2352)
			(stroke
				(width 0.1524)
				(type default)
			)
			(layer "B.SilkS")
		)
		(fp_line
			(start -1.016 -2.2352)
			(end -1.016 -0.8382)
			(stroke
				(width 0.1524)
				(type default)
			)
			(layer "B.SilkS")
		)
		(fp_line
			(start 1.016 -2.2352)
			(end -1.016 -2.2352)
			(stroke
				(width 0.1524)
				(type default)
			)
			(layer "B.SilkS")
		)
		(fp_rect
			(start 1.0922 2.3114)
			(end -1.0922 -2.3114)
			(stroke
				(width 0)
				(type default)
			)
			(fill no)
			(layer "B.CrtYd")
		)
		(fp_poly
			(pts
				(xy -1.0922 -2.3114) (xy -1.0922 2.3114) (xy 1.0922 2.3114) (xy 1.0922 -2.3114)
			)
			(stroke
				(width 0)
				(type default)
			)
			(fill no)
			(layer "B.Fab")
		)
		(pad "1" smd rect
			(at 0 -1.397 90)
			(size 1.651 1.27)
			(layers "B.Cu" "B.Mask" "B.Paste")
			(net "VT235_VDDL")
		)
		(pad "2" smd rect
			(at 0 1.397 90)
			(size 1.651 1.27)
			(layers "B.Cu" "B.Mask" "B.Paste")
			(net "GND")
		)
	)
	(footprint ""
		(layer "B.Cu")
		(at 199.771 -35.3314 180)
		(property "Reference" "R186"
			(at 0 0 0)
			(layer "B.SilkS")
			(hide yes)
			(effects
				(font
					(size 1.27 1.27)
				)
				(justify mirror)
			)
		)
		(property "Value" "4K7R2F-GP"
			(at -0.064008 -3.993896 180)
			(unlocked yes)
			(layer "B.Fab")
			(hide yes)
			(effects
				(font
					(size 1.016 1.016)
					(thickness 0.1524)
				)
				(justify mirror)
			)
		)
		(property "Device Type" "R402H16"
			(at -0.064008 -5.517896 180)
			(unlocked yes)
			(layer "B.Fab")
			(hide yes)
			(effects
				(font
					(size 1.016 1.016)
					(thickness 0.1524)
				)
				(justify mirror)
			)
		)
		(duplicate_pad_numbers_are_jumpers no)
		(fp_line
			(start 0.508 -0.9398)
			(end 0.508 0.9398)
			(stroke
				(width 0.1524)
				(type default)
			)
			(layer "B.SilkS")
		)
		(fp_line
			(start -0.508 -0.9398)
			(end 0.508 -0.9398)
			(stroke
				(width 0.1524)
				(type default)
			)
			(layer "B.SilkS")
		)
		(fp_rect
			(start 0.508 0.9398)
			(end -0.508 -0.9398)
			(stroke
				(width 0)
				(type default)
			)
			(fill no)
			(layer "B.CrtYd")
		)
		(fp_rect
			(start 0.508 0.9398)
			(end -0.508 -0.9398)
			(stroke
				(width 0)
				(type default)
			)
			(fill no)
			(layer "B.Fab")
		)
		(pad "1" smd custom
			(at 0 -0.4445)
			(size 0.1397 0.1397)
			(layers "B.Cu" "B.Mask" "B.Paste")
			(net "P1V8_C")
			(options
				(clearance outline)
				(anchor circle)
			)
			(primitives
				(gr_poly
					(pts
						(arc
							(start -0.1778 0.2794)
							(mid -0.249642 0.249642)
							(end -0.2794 0.1778)
						)
						(arc
							(start -0.2794 -0.1778)
							(mid -0.249642 -0.249642)
							(end -0.1778 -0.2794)
						)
						(arc
							(start 0.1778 -0.2794)
							(mid 0.249642 -0.249642)
							(end 0.2794 -0.1778)
						)
						(arc
							(start 0.2794 0.1778)
							(mid 0.249642 0.249642)
							(end 0.1778 0.2794)
						)
					)
					(width 0)
					(fill yes)
				)
			)
		)
		(pad "2" smd custom
			(at 0 0.4445)
			(size 0.1397 0.1397)
			(layers "B.Cu" "B.Mask" "B.Paste")
			(net "IOC_EEPROM_A2")
			(options
				(clearance outline)
				(anchor circle)
			)
			(primitives
				(gr_poly
					(pts
						(arc
							(start -0.1778 0.2794)
							(mid -0.249642 0.249642)
							(end -0.2794 0.1778)
						)
						(arc
							(start -0.2794 -0.1778)
							(mid -0.249642 -0.249642)
							(end -0.1778 -0.2794)
						)
						(arc
							(start 0.1778 -0.2794)
							(mid 0.249642 -0.249642)
							(end 0.2794 -0.1778)
						)
						(arc
							(start 0.2794 0.1778)
							(mid 0.249642 0.249642)
							(end 0.1778 0.2794)
						)
					)
					(width 0)
					(fill yes)
				)
			)
		)
	)
	(footprint ""
		(layer "B.Cu")
		(at 172.122338 -43.47845 -90)
		(property "Reference" "C442"
			(at 0 0 90)
			(layer "B.SilkS")
			(hide yes)
			(effects
				(font
					(size 1.27 1.27)
				)
				(justify mirror)
			)
		)
		(property "Value" "SCD1U6D3V1KX-GP"
			(at 2.8321 -1.7399 270)
			(unlocked yes)
			(layer "B.Fab")
			(hide yes)
			(effects
				(font
					(size 1.016 1.016)
					(thickness 0.1524)
				)
				(justify mirror)
			)
		)
		(property "Device Type" "C0201H13"
			(at 2.8321 -3.2639 270)
			(unlocked yes)
			(layer "B.Fab")
			(hide yes)
			(effects
				(font
					(size 1.016 1.016)
					(thickness 0.1524)
				)
				(justify mirror)
			)
		)
		(duplicate_pad_numbers_are_jumpers no)
		(fp_rect
			(start 0.2794 0.6477)
			(end -0.2794 -0.6477)
			(stroke
				(width 0)
				(type default)
			)
			(fill no)
			(layer "B.CrtYd")
		)
		(fp_rect
			(start 0.2794 0.6477)
			(end -0.2794 -0.6477)
			(stroke
				(width 0)
				(type default)
			)
			(fill no)
			(layer "B.Fab")
		)
		(pad "1" smd custom
			(at 0 -0.2794 90)
			(size 0.0762 0.0762)
			(layers "B.Cu" "B.Mask" "B.Paste")
			(net "P0V975")
			(options
				(clearance outline)
				(anchor circle)
			)
			(primitives
				(gr_poly
					(pts
						(arc
							(start 0.1524 0.127)
							(mid 0.137521 0.162921)
							(end 0.1016 0.1778)
						)
						(arc
							(start -0.1016 0.1778)
							(mid -0.137521 0.162921)
							(end -0.1524 0.127)
						)
						(arc
							(start -0.1524 -0.127)
							(mid -0.137521 -0.162921)
							(end -0.1016 -0.1778)
						)
						(arc
							(start 0.1016 -0.1778)
							(mid 0.137521 -0.162921)
							(end 0.1524 -0.127)
						)
					)
					(width 0)
					(fill yes)
				)
			)
		)
		(pad "2" smd custom
			(at 0 0.2794 90)
			(size 0.0762 0.0762)
			(layers "B.Cu" "B.Mask" "B.Paste")
			(net "GND")
			(options
				(clearance outline)
				(anchor circle)
			)
			(primitives
				(gr_poly
					(pts
						(arc
							(start 0.1524 0.127)
							(mid 0.137521 0.162921)
							(end 0.1016 0.1778)
						)
						(arc
							(start -0.1016 0.1778)
							(mid -0.137521 0.162921)
							(end -0.1524 0.127)
						)
						(arc
							(start -0.1524 -0.127)
							(mid -0.137521 -0.162921)
							(end -0.1016 -0.1778)
						)
						(arc
							(start 0.1016 -0.1778)
							(mid 0.137521 -0.162921)
							(end 0.1524 -0.127)
						)
					)
					(width 0)
					(fill yes)
				)
			)
		)
	)
	(footprint ""
		(layer "B.Cu")
		(at 127.970788 -54.502304 -90)
		(property "Reference" "C273"
			(at 0 0 90)
			(layer "B.SilkS")
			(hide yes)
			(effects
				(font
					(size 1.27 1.27)
				)
				(justify mirror)
			)
		)
		(property "Value" "SCD1U6D3V1KX-GP"
			(at 2.8321 -1.7399 270)
			(unlocked yes)
			(layer "B.Fab")
			(hide yes)
			(effects
				(font
					(size 1.016 1.016)
					(thickness 0.1524)
				)
				(justify mirror)
			)
		)
		(property "Device Type" "C0201H13"
			(at 2.8321 -3.2639 270)
			(unlocked yes)
			(layer "B.Fab")
			(hide yes)
			(effects
				(font
					(size 1.016 1.016)
					(thickness 0.1524)
				)
				(justify mirror)
			)
		)
		(duplicate_pad_numbers_are_jumpers no)
		(fp_rect
			(start 0.2794 0.6477)
			(end -0.2794 -0.6477)
			(stroke
				(width 0)
				(type default)
			)
			(fill no)
			(layer "B.CrtYd")
		)
		(fp_rect
			(start 0.2794 0.6477)
			(end -0.2794 -0.6477)
			(stroke
				(width 0)
				(type default)
			)
			(fill no)
			(layer "B.Fab")
		)
		(pad "1" smd custom
			(at 0 -0.2794 90)
			(size 0.0762 0.0762)
			(layers "B.Cu" "B.Mask" "B.Paste")
			(net "GB_VDDA")
			(options
				(clearance outline)
				(anchor circle)
			)
			(primitives
				(gr_poly
					(pts
						(arc
							(start 0.1524 0.127)
							(mid 0.137521 0.162921)
							(end 0.1016 0.1778)
						)
						(arc
							(start -0.1016 0.1778)
							(mid -0.137521 0.162921)
							(end -0.1524 0.127)
						)
						(arc
							(start -0.1524 -0.127)
							(mid -0.137521 -0.162921)
							(end -0.1016 -0.1778)
						)
						(arc
							(start 0.1016 -0.1778)
							(mid 0.137521 -0.162921)
							(end 0.1524 -0.127)
						)
					)
					(width 0)
					(fill yes)
				)
			)
		)
		(pad "2" smd custom
			(at 0 0.2794 90)
			(size 0.0762 0.0762)
			(layers "B.Cu" "B.Mask" "B.Paste")
			(net "GND")
			(options
				(clearance outline)
				(anchor circle)
			)
			(primitives
				(gr_poly
					(pts
						(arc
							(start 0.1524 0.127)
							(mid 0.137521 0.162921)
							(end 0.1016 0.1778)
						)
						(arc
							(start -0.1016 0.1778)
							(mid -0.137521 0.162921)
							(end -0.1524 0.127)
						)
						(arc
							(start -0.1524 -0.127)
							(mid -0.137521 -0.162921)
							(end -0.1016 -0.1778)
						)
						(arc
							(start 0.1016 -0.1778)
							(mid 0.137521 -0.162921)
							(end 0.1524 -0.127)
						)
					)
					(width 0)
					(fill yes)
				)
			)
		)
	)
	(footprint ""
		(layer "B.Cu")
		(at 141.732 -88.9)
		(property "Reference" "R67"
			(at 0 0 0)
			(layer "B.SilkS")
			(hide yes)
			(effects
				(font
					(size 1.27 1.27)
				)
				(justify mirror)
			)
		)
		(property "Value" "1KR2F-3-GP"
			(at -0.064008 -3.993896 0)
			(unlocked yes)
			(layer "B.Fab")
			(hide yes)
			(effects
				(font
					(size 1.016 1.016)
					(thickness 0.1524)
				)
				(justify mirror)
			)
		)
		(property "Device Type" "R402H16"
			(at -0.064008 -5.517896 0)
			(unlocked yes)
			(layer "B.Fab")
			(hide yes)
			(effects
				(font
					(size 1.016 1.016)
					(thickness 0.1524)
				)
				(justify mirror)
			)
		)
		(duplicate_pad_numbers_are_jumpers no)
		(fp_line
			(start -0.508 -0.9398)
			(end 0.508 -0.9398)
			(stroke
				(width 0.1524)
				(type default)
			)
			(layer "B.SilkS")
		)
		(fp_line
			(start 0.508 -0.9398)
			(end 0.508 0.9398)
			(stroke
				(width 0.1524)
				(type default)
			)
			(layer "B.SilkS")
		)
		(fp_rect
			(start 0.508 0.9398)
			(end -0.508 -0.9398)
			(stroke
				(width 0)
				(type default)
			)
			(fill no)
			(layer "B.CrtYd")
		)
		(fp_rect
			(start 0.508 0.9398)
			(end -0.508 -0.9398)
			(stroke
				(width 0)
				(type default)
			)
			(fill no)
			(layer "B.Fab")
		)
		(pad "1" smd custom
			(at 0 -0.4445 180)
			(size 0.1397 0.1397)
			(layers "B.Cu" "B.Mask" "B.Paste")
			(net "P1V8_E")
			(options
				(clearance outline)
				(anchor circle)
			)
			(primitives
				(gr_poly
					(pts
						(arc
							(start -0.1778 0.2794)
							(mid -0.249642 0.249642)
							(end -0.2794 0.1778)
						)
						(arc
							(start -0.2794 -0.1778)
							(mid -0.249642 -0.249642)
							(end -0.1778 -0.2794)
						)
						(arc
							(start 0.1778 -0.2794)
							(mid 0.249642 -0.249642)
							(end 0.2794 -0.1778)
						)
						(arc
							(start 0.2794 0.1778)
							(mid 0.249642 0.249642)
							(end 0.1778 0.2794)
						)
					)
					(width 0)
					(fill yes)
				)
			)
		)
		(pad "2" smd custom
			(at 0 0.4445 180)
			(size 0.1397 0.1397)
			(layers "B.Cu" "B.Mask" "B.Paste")
			(net "EXP_I2C_SDA9")
			(options
				(clearance outline)
				(anchor circle)
			)
			(primitives
				(gr_poly
					(pts
						(arc
							(start -0.1778 0.2794)
							(mid -0.249642 0.249642)
							(end -0.2794 0.1778)
						)
						(arc
							(start -0.2794 -0.1778)
							(mid -0.249642 -0.249642)
							(end -0.1778 -0.2794)
						)
						(arc
							(start 0.1778 -0.2794)
							(mid 0.249642 -0.249642)
							(end 0.2794 -0.1778)
						)
						(arc
							(start 0.2794 0.1778)
							(mid 0.249642 0.249642)
							(end 0.1778 0.2794)
						)
					)
					(width 0)
					(fill yes)
				)
			)
		)
	)
)
